(kicad_pcb
	(version 20241229)
	(generator "pcbnew")
	(generator_version "9.0")
	(general
		(thickness 1.6642)
		(legacy_teardrops no)
	)
	(paper "A3")
	(title_block
		(title "PolarFire SoM")
		(date "2025-07-22")
		(rev "1.1.4")
		(company "Antmicro Ltd")
		(comment 1 "www.antmicro.com")
		(comment 9 "footprint 74 of 470 (U12), pads 1-82 of 200")
	)
	(layers
		(0 "F.Cu" mixed)
		(4 "In1.Cu" power)
		(6 "In2.Cu" signal)
		(8 "In3.Cu" power)
		(10 "In4.Cu" signal)
		(12 "In5.Cu" power)
		(14 "In6.Cu" power)
		(16 "In7.Cu" signal)
		(18 "In8.Cu" power)
		(20 "In9.Cu" signal)
		(22 "In10.Cu" power)
		(24 "In11.Cu" signal)
		(26 "In12.Cu" signal)
		(2 "B.Cu" mixed)
		(9 "F.Adhes" user "F.Adhesive")
		(11 "B.Adhes" user "B.Adhesive")
		(13 "F.Paste" user)
		(15 "B.Paste" user)
		(5 "F.SilkS" user "F.Silkscreen")
		(7 "B.SilkS" user "B.Silkscreen")
		(1 "F.Mask" user)
		(3 "B.Mask" user)
		(17 "Dwgs.User" user "User.Drawings")
		(19 "Cmts.User" user "User.Comments")
		(21 "Eco1.User" user "User.Eco1")
		(23 "Eco2.User" user "User.Eco2")
		(25 "Edge.Cuts" user)
		(27 "Margin" user)
		(31 "F.CrtYd" user "F.Courtyard")
		(29 "B.CrtYd" user "B.Courtyard")
		(35 "F.Fab" user)
		(33 "B.Fab" user)
	)
	(footprint "antmicro-footprints:BGA-200_10.0x14.5mm_Layout12x22_P0.80x0.65mm"
		(layer "F.Cu")
		(at 180 129.6)
		(descr "BGA-200, 14.5x10.0mm, 200 Ball, 12x22 Layout, 0.8x0.65mm Pitch, http://www.issi.com/WW/pdf/43-46LQ32256A-AL.pdf")
		(tags "BGA 200 0.8x0.65")
		(property "Reference" "U12"
			(at 6.26 1.53 270)
			(layer "F.SilkS")
			(effects
				(font
					(size 0.7 0.7)
					(thickness 0.15)
				)
				(justify left bottom)
			)
		)
		(property "Value" "MT53D512M32D2_WFBGA"
			(at -5.5 9 0)
			(layer "F.Fab")
			(hide yes)
			(effects
				(font
					(size 0.7 0.7)
					(thickness 0.15)
				)
				(justify left bottom)
			)
		)
		(property "Datasheet" "https://eu.mouser.com/datasheet/2/671/200b_z11m_non_auto_lpddr4_lpddr4x-3077547.pdf"
			(at 0 0 0)
			(layer "F.Fab")
			(hide yes)
			(effects
				(font
					(size 1.27 1.27)
					(thickness 0.15)
				)
			)
		)
		(property "Description" "LPDDR4 DRAM, 1GX32"
			(at 0 0 0)
			(layer "F.Fab")
			(hide yes)
			(effects
				(font
					(size 1.27 1.27)
					(thickness 0.15)
				)
			)
		)
		(property "Author" "Antmicro"
			(at 0 0 0)
			(layer "F.Fab")
			(hide yes)
			(effects
				(font
					(size 1 1)
					(thickness 0.15)
				)
			)
		)
		(property "License" "Apache-2.0"
			(at 0 0 0)
			(layer "F.Fab")
			(hide yes)
			(effects
				(font
					(size 1 1)
					(thickness 0.15)
				)
			)
		)
		(property "MPN" "MT53D512M32D2DS-053 WT:D TR"
			(at 0 0 0)
			(layer "F.Fab")
			(hide yes)
			(effects
				(font
					(size 1 1)
					(thickness 0.15)
				)
			)
		)
		(property "Manufacturer" "Micron Technology"
			(at 0 0 0)
			(layer "F.Fab")
			(hide yes)
			(effects
				(font
					(size 1 1)
					(thickness 0.15)
				)
			)
		)
		(property "VSD_class" "LPDDR4"
			(at 0 0 0)
			(layer "F.Fab")
			(hide yes)
			(effects
				(font
					(size 1 1)
					(thickness 0.15)
				)
			)
		)
		(property ki_fp_filters "WFBGA200_10X14p5_DS_MRN WFBGA200_10X14p5_DS_MRN-M WFBGA200_10X14p5_DS_MRN-L")
		(sheetname "/LPDDR4/")
		(sheetfile "lpddr.kicad_sch")
		(attr smd)
		(pad "A1" smd circle
			(at -4.396 -6.834)
			(size 0.27 0.27)
			(layers "F.Cu" "F.Mask" "F.Paste")
			(net 478 "unconnected-(U12A-DNU-PadA1)")
			(pinfunction "DNU")
			(pintype "no_connect")
		)
		(pad "A2" smd circle
			(at -3.596 -6.834)
			(size 0.27 0.27)
			(layers "F.Cu" "F.Mask" "F.Paste")
			(net 479 "unconnected-(U12A-DNU-PadA2)")
			(pinfunction "DNU")
			(pintype "no_connect")
		)
		(pad "A3" smd circle
			(at -2.795 -6.834)
			(size 0.27 0.27)
			(layers "F.Cu" "F.Mask" "F.Paste")
			(net 417 "GND")
			(pinfunction "VSS")
			(pintype "power_out")
		)
		(pad "A4" smd circle
			(at -1.996 -6.834)
			(size 0.27 0.27)
			(layers "F.Cu" "F.Mask" "F.Paste")
			(net 2 "+1V1")
			(pinfunction "VDD2")
			(pintype "power_in")
		)
		(pad "A5" smd circle
			(at -1.196 -6.834)
			(size 0.27 0.27)
			(layers "F.Cu" "F.Mask" "F.Paste")
			(net 271 "Net-(U12A-ZQ0)")
			(pinfunction "ZQ0")
			(pintype "unspecified")
		)
		(pad "A8" smd circle
			(at 1.205 -6.834)
			(size 0.27 0.27)
			(layers "F.Cu" "F.Mask" "F.Paste")
			(net 480 "unconnected-(U12B-NC-PadA8)")
			(pinfunction "NC")
			(pintype "no_connect")
		)
		(pad "A9" smd circle
			(at 2.004 -6.834)
			(size 0.27 0.27)
			(layers "F.Cu" "F.Mask" "F.Paste")
			(net 2 "+1V1")
			(pinfunction "VDD2")
			(pintype "passive")
		)
		(pad "A10" smd circle
			(at 2.805 -6.834)
			(size 0.27 0.27)
			(layers "F.Cu" "F.Mask" "F.Paste")
			(net 417 "GND")
			(pinfunction "VSS")
			(pintype "power_out")
		)
		(pad "A11" smd circle
			(at 3.604 -6.834)
			(size 0.27 0.27)
			(layers "F.Cu" "F.Mask" "F.Paste")
			(net 481 "unconnected-(U12B-DNU-PadA11)")
			(pinfunction "DNU")
			(pintype "no_connect")
		)
		(pad "A12" smd circle
			(at 4.405 -6.834)
			(size 0.27 0.27)
			(layers "F.Cu" "F.Mask" "F.Paste")
			(net 482 "unconnected-(U12B-DNU-PadA12)")
			(pinfunction "DNU")
			(pintype "no_connect")
		)
		(pad "AA1" smd circle
			(at -4.396 6.166)
			(size 0.27 0.27)
			(layers "F.Cu" "F.Mask" "F.Paste")
			(net 483 "unconnected-(U12B-DNU-PadAA1)")
			(pinfunction "DNU")
			(pintype "no_connect")
		)
		(pad "AA2" smd circle
			(at -3.596 6.166)
			(size 0.27 0.27)
			(layers "F.Cu" "F.Mask" "F.Paste")
			(net 613 "/FPGA MSS/LPDDR4.DQ16")
			(pinfunction "DQ0_B")
			(pintype "bidirectional")
		)
		(pad "AA3" smd circle
			(at -2.795 6.166)
			(size 0.27 0.27)
			(layers "F.Cu" "F.Mask" "F.Paste")
			(net 2 "+1V1")
			(pinfunction "VDDQ")
			(pintype "passive")
		)
		(pad "AA4" smd circle
			(at -1.996 6.166)
			(size 0.27 0.27)
			(layers "F.Cu" "F.Mask" "F.Paste")
			(net 606 "/FPGA MSS/LPDDR4.DQ23")
			(pinfunction "DQ7_B")
			(pintype "bidirectional")
		)
		(pad "AA5" smd circle
			(at -1.196 6.166)
			(size 0.27 0.27)
			(layers "F.Cu" "F.Mask" "F.Paste")
			(net 2 "+1V1")
			(pinfunction "VDDQ")
			(pintype "passive")
		)
		(pad "AA8" smd circle
			(at 1.205 6.166)
			(size 0.27 0.27)
			(layers "F.Cu" "F.Mask" "F.Paste")
			(net 2 "+1V1")
			(pinfunction "VDDQ")
			(pintype "passive")
		)
		(pad "AA9" smd circle
			(at 2.004 6.166)
			(size 0.27 0.27)
			(layers "F.Cu" "F.Mask" "F.Paste")
			(net 567 "/FPGA MSS/LPDDR4.DQ31")
			(pinfunction "DQ15_B")
			(pintype "bidirectional")
		)
		(pad "AA10" smd circle
			(at 2.805 6.166)
			(size 0.27 0.27)
			(layers "F.Cu" "F.Mask" "F.Paste")
			(net 2 "+1V1")
			(pinfunction "VDDQ")
			(pintype "power_in")
		)
		(pad "AA11" smd circle
			(at 3.604 6.166)
			(size 0.27 0.27)
			(layers "F.Cu" "F.Mask" "F.Paste")
			(net 594 "/FPGA MSS/LPDDR4.DQ24")
			(pinfunction "DQ8_B")
			(pintype "bidirectional")
		)
		(pad "AA12" smd circle
			(at 4.405 6.166)
			(size 0.27 0.27)
			(layers "F.Cu" "F.Mask" "F.Paste")
			(net 484 "unconnected-(U12B-DNU-PadAA12)")
			(pinfunction "DNU")
			(pintype "no_connect")
		)
		(pad "AB1" smd circle
			(at -4.396 6.817)
			(size 0.27 0.27)
			(layers "F.Cu" "F.Mask" "F.Paste")
			(net 485 "unconnected-(U12B-DNU-PadAB1)")
			(pinfunction "DNU")
			(pintype "no_connect")
		)
		(pad "AB2" smd circle
			(at -3.596 6.817)
			(size 0.27 0.27)
			(layers "F.Cu" "F.Mask" "F.Paste")
			(net 486 "unconnected-(U12B-DNU-PadAB2)")
			(pinfunction "DNU")
			(pintype "no_connect")
		)
		(pad "AB3" smd circle
			(at -2.795 6.817)
			(size 0.27 0.27)
			(layers "F.Cu" "F.Mask" "F.Paste")
			(net 417 "GND")
			(pinfunction "VSS")
			(pintype "passive")
		)
		(pad "AB4" smd circle
			(at -1.996 6.817)
			(size 0.27 0.27)
			(layers "F.Cu" "F.Mask" "F.Paste")
			(net 2 "+1V1")
			(pinfunction "VDD2")
			(pintype "power_in")
		)
		(pad "AB5" smd circle
			(at -1.196 6.817)
			(size 0.27 0.27)
			(layers "F.Cu" "F.Mask" "F.Paste")
			(net 417 "GND")
			(pinfunction "VSS")
			(pintype "passive")
		)
		(pad "AB8" smd circle
			(at 1.205 6.817)
			(size 0.27 0.27)
			(layers "F.Cu" "F.Mask" "F.Paste")
			(net 417 "GND")
			(pinfunction "VSS")
			(pintype "passive")
		)
		(pad "AB9" smd circle
			(at 2.004 6.817)
			(size 0.27 0.27)
			(layers "F.Cu" "F.Mask" "F.Paste")
			(net 2 "+1V1")
			(pinfunction "VDD2")
			(pintype "passive")
		)
		(pad "AB10" smd circle
			(at 2.805 6.817)
			(size 0.27 0.27)
			(layers "F.Cu" "F.Mask" "F.Paste")
			(net 417 "GND")
			(pinfunction "VSS")
			(pintype "passive")
		)
		(pad "AB11" smd circle
			(at 3.604 6.817)
			(size 0.27 0.27)
			(layers "F.Cu" "F.Mask" "F.Paste")
			(net 487 "unconnected-(U12B-DNU-PadAB11)")
			(pinfunction "DNU")
			(pintype "no_connect")
		)
		(pad "AB12" smd circle
			(at 4.405 6.817)
			(size 0.27 0.27)
			(layers "F.Cu" "F.Mask" "F.Paste")
			(net 488 "unconnected-(U12B-DNU-PadAB12)")
			(pinfunction "DNU")
			(pintype "no_connect")
		)
		(pad "B1" smd circle
			(at -4.396 -6.183)
			(size 0.27 0.27)
			(layers "F.Cu" "F.Mask" "F.Paste")
			(net 489 "unconnected-(U12A-DNU-PadB1)")
			(pinfunction "DNU")
			(pintype "no_connect")
		)
		(pad "B2" smd circle
			(at -3.596 -6.183)
			(size 0.27 0.27)
			(layers "F.Cu" "F.Mask" "F.Paste")
			(net 608 "/FPGA MSS/LPDDR4.DQ0")
			(pinfunction "DQ0_A")
			(pintype "bidirectional")
		)
		(pad "B3" smd circle
			(at -2.795 -6.183)
			(size 0.27 0.27)
			(layers "F.Cu" "F.Mask" "F.Paste")
			(net 2 "+1V1")
			(pinfunction "VDDQ")
			(pintype "power_in")
		)
		(pad "B4" smd circle
			(at -1.996 -6.183)
			(size 0.27 0.27)
			(layers "F.Cu" "F.Mask" "F.Paste")
			(net 319 "/FPGA MSS/LPDDR4.DQ7")
			(pinfunction "DQ7_A")
			(pintype "bidirectional")
		)
		(pad "B5" smd circle
			(at -1.196 -6.183)
			(size 0.27 0.27)
			(layers "F.Cu" "F.Mask" "F.Paste")
			(net 2 "+1V1")
			(pinfunction "VDDQ")
			(pintype "passive")
		)
		(pad "B8" smd circle
			(at 1.205 -6.183)
			(size 0.27 0.27)
			(layers "F.Cu" "F.Mask" "F.Paste")
			(net 2 "+1V1")
			(pinfunction "VDDQ")
			(pintype "passive")
		)
		(pad "B9" smd circle
			(at 2.004 -6.183)
			(size 0.27 0.27)
			(layers "F.Cu" "F.Mask" "F.Paste")
			(net 311 "/FPGA MSS/LPDDR4.DQ15")
			(pinfunction "DQ15_A")
			(pintype "bidirectional")
		)
		(pad "B10" smd circle
			(at 2.805 -6.183)
			(size 0.27 0.27)
			(layers "F.Cu" "F.Mask" "F.Paste")
			(net 2 "+1V1")
			(pinfunction "VDDQ")
			(pintype "passive")
		)
		(pad "B11" smd circle
			(at 3.604 -6.183)
			(size 0.27 0.27)
			(layers "F.Cu" "F.Mask" "F.Paste")
			(net 604 "/FPGA MSS/LPDDR4.DQ8")
			(pinfunction "DQ8_A")
			(pintype "bidirectional")
		)
		(pad "B12" smd circle
			(at 4.405 -6.183)
			(size 0.27 0.27)
			(layers "F.Cu" "F.Mask" "F.Paste")
			(net 490 "unconnected-(U12B-DNU-PadB12)")
			(pinfunction "DNU")
			(pintype "no_connect")
		)
		(pad "C1" smd circle
			(at -4.396 -5.534)
			(size 0.27 0.27)
			(layers "F.Cu" "F.Mask" "F.Paste")
			(net 417 "GND")
			(pinfunction "VSS")
			(pintype "passive")
		)
		(pad "C2" smd circle
			(at -3.596 -5.534)
			(size 0.27 0.27)
			(layers "F.Cu" "F.Mask" "F.Paste")
			(net 609 "/FPGA MSS/LPDDR4.DQ1")
			(pinfunction "DQ1_A")
			(pintype "bidirectional")
		)
		(pad "C3" smd circle
			(at -2.795 -5.534)
			(size 0.27 0.27)
			(layers "F.Cu" "F.Mask" "F.Paste")
			(net 320 "/FPGA MSS/LPDDR4.DMI0")
			(pinfunction "DMI0_A")
			(pintype "bidirectional")
		)
		(pad "C4" smd circle
			(at -1.996 -5.534)
			(size 0.27 0.27)
			(layers "F.Cu" "F.Mask" "F.Paste")
			(net 316 "/FPGA MSS/LPDDR4.DQ6")
			(pinfunction "DQ6_A")
			(pintype "bidirectional")
		)
		(pad "C5" smd circle
			(at -1.196 -5.534)
			(size 0.27 0.27)
			(layers "F.Cu" "F.Mask" "F.Paste")
			(net 417 "GND")
			(pinfunction "VSS")
			(pintype "passive")
		)
		(pad "C8" smd circle
			(at 1.205 -5.534)
			(size 0.27 0.27)
			(layers "F.Cu" "F.Mask" "F.Paste")
			(net 417 "GND")
			(pinfunction "VSS")
			(pintype "passive")
		)
		(pad "C9" smd circle
			(at 2.004 -5.534)
			(size 0.27 0.27)
			(layers "F.Cu" "F.Mask" "F.Paste")
			(net 612 "/FPGA MSS/LPDDR4.DQ14")
			(pinfunction "DQ14_A")
			(pintype "bidirectional")
		)
		(pad "C10" smd circle
			(at 2.805 -5.534)
			(size 0.27 0.27)
			(layers "F.Cu" "F.Mask" "F.Paste")
			(net 310 "/FPGA MSS/LPDDR4.DMI1")
			(pinfunction "DMI1_A")
			(pintype "bidirectional")
		)
		(pad "C11" smd circle
			(at 3.604 -5.534)
			(size 0.27 0.27)
			(layers "F.Cu" "F.Mask" "F.Paste")
			(net 603 "/FPGA MSS/LPDDR4.DQ9")
			(pinfunction "DQ9_A")
			(pintype "bidirectional")
		)
		(pad "C12" smd circle
			(at 4.405 -5.534)
			(size 0.27 0.27)
			(layers "F.Cu" "F.Mask" "F.Paste")
			(net 417 "GND")
			(pinfunction "VSS")
			(pintype "passive")
		)
		(pad "D1" smd circle
			(at -4.396 -4.883)
			(size 0.27 0.27)
			(layers "F.Cu" "F.Mask" "F.Paste")
			(net 2 "+1V1")
			(pinfunction "VDDQ")
			(pintype "passive")
		)
		(pad "D2" smd circle
			(at -3.596 -4.883)
			(size 0.27 0.27)
			(layers "F.Cu" "F.Mask" "F.Paste")
			(net 417 "GND")
			(pinfunction "VSS")
			(pintype "passive")
		)
		(pad "D3" smd circle
			(at -2.795 -4.883)
			(size 0.27 0.27)
			(layers "F.Cu" "F.Mask" "F.Paste")
			(net 306 "/FPGA MSS/LPDDR4.DQS0_P")
			(pinfunction "DQS0_t_A")
			(pintype "bidirectional")
		)
		(pad "D4" smd circle
			(at -1.996 -4.883)
			(size 0.27 0.27)
			(layers "F.Cu" "F.Mask" "F.Paste")
			(net 417 "GND")
			(pinfunction "VSS")
			(pintype "passive")
		)
		(pad "D5" smd circle
			(at -1.196 -4.883)
			(size 0.27 0.27)
			(layers "F.Cu" "F.Mask" "F.Paste")
			(net 2 "+1V1")
			(pinfunction "VDDQ")
			(pintype "passive")
		)
		(pad "D8" smd circle
			(at 1.205 -4.883)
			(size 0.27 0.27)
			(layers "F.Cu" "F.Mask" "F.Paste")
			(net 2 "+1V1")
			(pinfunction "VDDQ")
			(pintype "passive")
		)
		(pad "D9" smd circle
			(at 2.004 -4.883)
			(size 0.27 0.27)
			(layers "F.Cu" "F.Mask" "F.Paste")
			(net 417 "GND")
			(pinfunction "VSS")
			(pintype "passive")
		)
		(pad "D10" smd circle
			(at 2.805 -4.883)
			(size 0.27 0.27)
			(layers "F.Cu" "F.Mask" "F.Paste")
			(net 611 "/FPGA MSS/LPDDR4.DQS1_P")
			(pinfunction "DQS1_t_A")
			(pintype "bidirectional")
		)
		(pad "D11" smd circle
			(at 3.604 -4.883)
			(size 0.27 0.27)
			(layers "F.Cu" "F.Mask" "F.Paste")
			(net 417 "GND")
			(pinfunction "VSS")
			(pintype "passive")
		)
		(pad "D12" smd circle
			(at 4.405 -4.883)
			(size 0.27 0.27)
			(layers "F.Cu" "F.Mask" "F.Paste")
			(net 2 "+1V1")
			(pinfunction "VDDQ")
			(pintype "passive")
		)
		(pad "E1" smd circle
			(at -4.396 -4.233)
			(size 0.27 0.27)
			(layers "F.Cu" "F.Mask" "F.Paste")
			(net 417 "GND")
			(pinfunction "VSS")
			(pintype "passive")
		)
		(pad "E2" smd circle
			(at -3.596 -4.233)
			(size 0.27 0.27)
			(layers "F.Cu" "F.Mask" "F.Paste")
			(net 607 "/FPGA MSS/LPDDR4.DQ2")
			(pinfunction "DQ2_A")
			(pintype "bidirectional")
		)
		(pad "E3" smd circle
			(at -2.795 -4.233)
			(size 0.27 0.27)
			(layers "F.Cu" "F.Mask" "F.Paste")
			(net 307 "/FPGA MSS/LPDDR4.DQS0_N")
			(pinfunction "DQS0_c_A")
			(pintype "bidirectional")
		)
		(pad "E4" smd circle
			(at -1.996 -4.233)
			(size 0.27 0.27)
			(layers "F.Cu" "F.Mask" "F.Paste")
			(net 308 "/FPGA MSS/LPDDR4.DQ5")
			(pinfunction "DQ5_A")
			(pintype "bidirectional")
		)
		(pad "E5" smd circle
			(at -1.196 -4.233)
			(size 0.27 0.27)
			(layers "F.Cu" "F.Mask" "F.Paste")
			(net 417 "GND")
			(pinfunction "VSS")
			(pintype "passive")
		)
		(pad "E8" smd circle
			(at 1.205 -4.233)
			(size 0.27 0.27)
			(layers "F.Cu" "F.Mask" "F.Paste")
			(net 417 "GND")
			(pinfunction "VSS")
			(pintype "passive")
		)
		(pad "E9" smd circle
			(at 2.004 -4.233)
			(size 0.27 0.27)
			(layers "F.Cu" "F.Mask" "F.Paste")
			(net 323 "/FPGA MSS/LPDDR4.DQ13")
			(pinfunction "DQ13_A")
			(pintype "bidirectional")
		)
		(pad "E10" smd circle
			(at 2.805 -4.233)
			(size 0.27 0.27)
			(layers "F.Cu" "F.Mask" "F.Paste")
			(net 602 "/FPGA MSS/LPDDR4.DQS1_N")
			(pinfunction "DQS1_c_A")
			(pintype "bidirectional")
		)
		(pad "E11" smd circle
			(at 3.604 -4.233)
			(size 0.27 0.27)
			(layers "F.Cu" "F.Mask" "F.Paste")
			(net 321 "/FPGA MSS/LPDDR4.DQ10")
			(pinfunction "DQ10_A")
			(pintype "bidirectional")
		)
		(pad "E12" smd circle
			(at 4.405 -4.233)
			(size 0.27 0.27)
			(layers "F.Cu" "F.Mask" "F.Paste")
			(net 417 "GND")
			(pinfunction "VSS")
			(pintype "passive")
		)
		(pad "F1" smd circle
			(at -4.396 -3.584)
			(size 0.27 0.27)
			(layers "F.Cu" "F.Mask" "F.Paste")
			(net 48 "+1V8")
			(pinfunction "VDD1")
			(pintype "power_in")
		)
		(pad "F2" smd circle
			(at -3.596 -3.584)
			(size 0.27 0.27)
			(layers "F.Cu" "F.Mask" "F.Paste")
			(net 305 "/FPGA MSS/LPDDR4.DQ3")
			(pinfunction "DQ3_A")
			(pintype "bidirectional")
		)
		(pad "F3" smd circle
			(at -2.795 -3.584)
			(size 0.27 0.27)
			(layers "F.Cu" "F.Mask" "F.Paste")
			(net 2 "+1V1")
			(pinfunction "VDDQ")
			(pintype "passive")
		)
		(pad "F4" smd circle
			(at -1.996 -3.584)
			(size 0.27 0.27)
			(layers "F.Cu" "F.Mask" "F.Paste")
			(net 610 "/FPGA MSS/LPDDR4.DQ4")
			(pinfunction "DQ4_A")
			(pintype "bidirectional")
		)
		(pad "F5" smd circle
			(at -1.196 -3.584)
			(size 0.27 0.27)
			(layers "F.Cu" "F.Mask" "F.Paste")
			(net 2 "+1V1")
			(pinfunction "VDD2")
			(pintype "passive")
		)
		(pad "F8" smd circle
			(at 1.205 -3.584)
			(size 0.27 0.27)
			(layers "F.Cu" "F.Mask" "F.Paste")
			(net 2 "+1V1")
			(pinfunction "VDD2")
			(pintype "passive")
		)
		(pad "F9" smd circle
			(at 2.004 -3.584)
			(size 0.27 0.27)
			(layers "F.Cu" "F.Mask" "F.Paste")
			(net 322 "/FPGA MSS/LPDDR4.DQ12")
			(pinfunction "DQ12_A")
			(pintype "bidirectional")
		)
		(pad "F10" smd circle
			(at 2.805 -3.584)
			(size 0.27 0.27)
			(layers "F.Cu" "F.Mask" "F.Paste")
			(net 2 "+1V1")
			(pinfunction "VDDQ")
			(pintype "passive")
		)
		(pad "F11" smd circle
			(at 3.604 -3.584)
			(size 0.27 0.27)
			(layers "F.Cu" "F.Mask" "F.Paste")
			(net 309 "/FPGA MSS/LPDDR4.DQ11")
			(pinfunction "DQ11_A")
			(pintype "bidirectional")
		)
		(pad "F12" smd circle
			(at 4.405 -3.584)
			(size 0.27 0.27)
			(layers "F.Cu" "F.Mask" "F.Paste")
			(net 48 "+1V8")
			(pinfunction "VDD1")
			(pintype "power_in")
		)
		(pad "G1" smd circle
			(at -4.396 -2.934)
			(size 0.27 0.27)
			(layers "F.Cu" "F.Mask" "F.Paste")
			(net 417 "GND")
			(pinfunction "VSS")
			(pintype "passive")
		)
		(pad "G2" smd circle
			(at -3.596 -2.934)
			(size 0.27 0.27)
			(layers "F.Cu" "F.Mask" "F.Paste")
			(net 393 "/FPGA MSS/LPDDR4.ODT_CA_A")
			(pinfunction "ODT_CA_A")
			(pintype "input")
		)
	)
)
